# S9S_MB_2U (Grand Teton) — schematic netlist excerpt (pin names and nets, part order shuffled) for the footprints in the layout excerpt that follows; sources: Cadence DE-HDL packaged netlist, KiCad conversion of 03242023_DA0F0TMBIJ0_F0T_Motherboard_J_brd_V01_OCP.brd

R367  Q_RES  1K 1% EMPTY  pkg 0402LF  page 198 : A = P3V3_AUX ; B = FM_PCH_SPKR
R3608  Q_RES  4.7K 1% CHIP  pkg 0402LF  page 172 : A = GND ; B = INA230_3_A1

(kicad_pcb
	(version 20260206)
	(generator "pcbnew")
	(generator_version "10.0")
	(general
		(thickness 1.6)
		(legacy_teardrops no)
	)
	(paper "A4")
	(title_block
		(title "03242023_DA0F0TMBIJ0_F0T_Motherboard_J_brd_V01_OCP.brd")
		(comment 1 "Grand Teton / footprints 296-297 of 6105")
	)
	(layers
		(0 "F.Cu" signal "TOP")
		(4 "In1.Cu" signal "GND")
		(6 "In2.Cu" signal "IN1")
		(8 "In3.Cu" signal "GND1")
		(10 "In4.Cu" signal "IN2")
		(12 "In5.Cu" signal "GND2")
		(14 "In6.Cu" signal "IN3")
		(16 "In7.Cu" signal "GND3")
		(18 "In8.Cu" signal "VCC")
		(20 "In9.Cu" signal "VCC1")
		(22 "In10.Cu" signal "GND4")
		(24 "In11.Cu" signal "IN4")
		(26 "In12.Cu" signal "GND5")
		(28 "In13.Cu" signal "IN5")
		(30 "In14.Cu" signal "GND6")
		(32 "In15.Cu" signal "IN6")
		(34 "In16.Cu" signal "GND7")
		(2 "B.Cu" signal "BOTTOM")
		(9 "F.Adhes" user "F.Adhesive")
		(11 "B.Adhes" user "B.Adhesive")
		(13 "F.Paste" user "Package Geometry/Pastemask Top")
		(15 "B.Paste" user "Package Geometry/Pastemask Bottom")
		(5 "F.SilkS" user "Ref Des/Silkscreen Top")
		(7 "B.SilkS" user "Ref Des/Silkscreen Bottom")
		(1 "F.Mask" user "Board Geometry/Soldermask Top")
		(3 "B.Mask" user "Board Geometry/Soldermask Bottom")
		(17 "Dwgs.User" user "User.Drawings")
		(19 "Cmts.User" user "User.Comments")
		(21 "Eco1.User" user "User.Eco1")
		(23 "Eco2.User" user "User.Eco2")
		(25 "Edge.Cuts" user "Board Geometry/Outline")
		(27 "Margin" user)
		(31 "F.CrtYd" user "Package Geometry/Place Bound Top")
		(29 "B.CrtYd" user "Package Geometry/Place Bound Bottom")
		(35 "F.Fab" user "Ref Des/Assembly Top")
		(33 "B.Fab" user "Ref Des/Assembly Bottom")
	)
	(footprint ""
		(layer "F.Cu")
		(at 68.212462 -40.437562)
		(property "Reference" "R3608"
			(at 0 0 0)
			(layer "F.SilkS")
			(hide yes)
			(effects
				(font
					(size 1.27 1.27)
				)
			)
		)
		(property "Value" ""
			(at 0 0 0)
			(layer "F.Fab")
			(effects
				(font
					(size 1.27 1.27)
				)
			)
		)
		(duplicate_pad_numbers_are_jumpers no)
		(fp_line
			(start -0.7874 -0.4064)
			(end 0.7874 -0.4064)
			(stroke
				(width 0.1524)
				(type default)
			)
			(layer "F.SilkS")
		)
		(fp_line
			(start -0.7874 0.4064)
			(end -0.7874 -0.4064)
			(stroke
				(width 0.1524)
				(type default)
			)
			(layer "F.SilkS")
		)
		(fp_line
			(start 0.7874 -0.4064)
			(end 0.7874 0.4064)
			(stroke
				(width 0.1524)
				(type default)
			)
			(layer "F.SilkS")
		)
		(fp_line
			(start 0.7874 0.4064)
			(end -0.7874 0.4064)
			(stroke
				(width 0.1524)
				(type default)
			)
			(layer "F.SilkS")
		)
		(fp_line
			(start -0.67945 -0.305054)
			(end -0.12065 -0.305054)
			(stroke
				(width 0.1)
				(type default)
			)
			(layer "F.Fab")
		)
		(fp_line
			(start -0.67945 0.3048)
			(end -0.67945 -0.305054)
			(stroke
				(width 0.1)
				(type default)
			)
			(layer "F.Fab")
		)
		(fp_line
			(start -0.12065 -0.305054)
			(end -0.12065 -0.2794)
			(stroke
				(width 0.1)
				(type default)
			)
			(layer "F.Fab")
		)
		(fp_line
			(start -0.12065 -0.2794)
			(end 0.12065 -0.2794)
			(stroke
				(width 0.1)
				(type default)
			)
			(layer "F.Fab")
		)
		(fp_line
			(start -0.12065 0.2794)
			(end -0.12065 0.3048)
			(stroke
				(width 0.1)
				(type default)
			)
			(layer "F.Fab")
		)
		(fp_line
			(start -0.12065 0.3048)
			(end -0.67945 0.3048)
			(stroke
				(width 0.1)
				(type default)
			)
			(layer "F.Fab")
		)
		(fp_line
			(start 0.120396 0.2794)
			(end -0.12065 0.2794)
			(stroke
				(width 0.1)
				(type default)
			)
			(layer "F.Fab")
		)
		(fp_line
			(start 0.120396 0.3048)
			(end 0.120396 0.2794)
			(stroke
				(width 0.1)
				(type default)
			)
			(layer "F.Fab")
		)
		(fp_line
			(start 0.12065 -0.3048)
			(end 0.67945 -0.3048)
			(stroke
				(width 0.1)
				(type default)
			)
			(layer "F.Fab")
		)
		(fp_line
			(start 0.12065 -0.2794)
			(end 0.12065 -0.3048)
			(stroke
				(width 0.1)
				(type default)
			)
			(layer "F.Fab")
		)
		(fp_line
			(start 0.67945 -0.3048)
			(end 0.67945 0.3048)
			(stroke
				(width 0.1)
				(type default)
			)
			(layer "F.Fab")
		)
		(fp_line
			(start 0.67945 0.3048)
			(end 0.120396 0.3048)
			(stroke
				(width 0.1)
				(type default)
			)
			(layer "F.Fab")
		)
		(pad "1" smd circle
			(at -0.40005 0)
			(size 0 0)
			(layers "F.Cu" "F.Mask" "F.Paste")
			(net "GND")
		)
		(pad "2" smd circle
			(at 0.40005 0)
			(size 0 0)
			(layers "F.Cu" "F.Mask" "F.Paste")
			(net "INA230_3_A1")
		)
	)
	(footprint ""
		(layer "F.Cu")
		(at 128.3843 -21.951188)
		(property "Reference" "R367"
			(at 0 0 0)
			(layer "F.SilkS")
			(hide yes)
			(effects
				(font
					(size 1.27 1.27)
				)
			)
		)
		(property "Value" ""
			(at 0 0 0)
			(layer "F.Fab")
			(effects
				(font
					(size 1.27 1.27)
				)
			)
		)
		(duplicate_pad_numbers_are_jumpers no)
		(fp_line
			(start -0.7874 -0.4064)
			(end 0.7874 -0.4064)
			(stroke
				(width 0.1524)
				(type default)
			)
			(layer "F.SilkS")
		)
		(fp_line
			(start -0.7874 0.4064)
			(end -0.7874 -0.4064)
			(stroke
				(width 0.1524)
				(type default)
			)
			(layer "F.SilkS")
		)
		(fp_line
			(start 0.7874 -0.4064)
			(end 0.7874 0.4064)
			(stroke
				(width 0.1524)
				(type default)
			)
			(layer "F.SilkS")
		)
		(fp_line
			(start 0.7874 0.4064)
			(end -0.7874 0.4064)
			(stroke
				(width 0.1524)
				(type default)
			)
			(layer "F.SilkS")
		)
		(fp_line
			(start -0.67945 -0.305054)
			(end -0.12065 -0.305054)
			(stroke
				(width 0.1)
				(type default)
			)
			(layer "F.Fab")
		)
		(fp_line
			(start -0.67945 0.3048)
			(end -0.67945 -0.305054)
			(stroke
				(width 0.1)
				(type default)
			)
			(layer "F.Fab")
		)
		(fp_line
			(start -0.12065 -0.305054)
			(end -0.12065 -0.2794)
			(stroke
				(width 0.1)
				(type default)
			)
			(layer "F.Fab")
		)
		(fp_line
			(start -0.12065 -0.2794)
			(end 0.12065 -0.2794)
			(stroke
				(width 0.1)
				(type default)
			)
			(layer "F.Fab")
		)
		(fp_line
			(start -0.12065 0.2794)
			(end -0.12065 0.3048)
			(stroke
				(width 0.1)
				(type default)
			)
			(layer "F.Fab")
		)
		(fp_line
			(start -0.12065 0.3048)
			(end -0.67945 0.3048)
			(stroke
				(width 0.1)
				(type default)
			)
			(layer "F.Fab")
		)
		(fp_line
			(start 0.120396 0.2794)
			(end -0.12065 0.2794)
			(stroke
				(width 0.1)
				(type default)
			)
			(layer "F.Fab")
		)
		(fp_line
			(start 0.120396 0.3048)
			(end 0.120396 0.2794)
			(stroke
				(width 0.1)
				(type default)
			)
			(layer "F.Fab")
		)
		(fp_line
			(start 0.12065 -0.3048)
			(end 0.67945 -0.3048)
			(stroke
				(width 0.1)
				(type default)
			)
			(layer "F.Fab")
		)
		(fp_line
			(start 0.12065 -0.2794)
			(end 0.12065 -0.3048)
			(stroke
				(width 0.1)
				(type default)
			)
			(layer "F.Fab")
		)
		(fp_line
			(start 0.67945 -0.3048)
			(end 0.67945 0.3048)
			(stroke
				(width 0.1)
				(type default)
			)
			(layer "F.Fab")
		)
		(fp_line
			(start 0.67945 0.3048)
			(end 0.120396 0.3048)
			(stroke
				(width 0.1)
				(type default)
			)
			(layer "F.Fab")
		)
		(pad "1" smd circle
			(at -0.40005 0)
			(size 0 0)
			(layers "F.Cu" "F.Mask" "F.Paste")
			(net "P3V3_AUX")
		)
		(pad "2" smd circle
			(at 0.40005 0)
			(size 0 0)
			(layers "F.Cu" "F.Mask" "F.Paste")
			(net "FM_PCH_SPKR")
		)
	)
)
